# BASEBOARD_FAB2 (Tioga Pass) — schematic netlist excerpt (pin names and nets, part order shuffled) for the footprints in the layout excerpt that follows; sources: Cadence DE-HDL packaged netlist, KiCad conversion of Wiwynn_Tioga_Pass_MB.brd

C30W6  SC22U16V5MX-4-GP  20%  pkg SMD-BCG5  page 253 : \1\ = P5V_STBY_USBC ; \2\ = GND
C8A2  CAP  220PF 50V 10% X7R  pkg 0402LF  page 235 : A = VR_PVNN_PCH_AVSP ; B = VSENSE_PVNN_PCH_STBY_AVSN
R8C4  RES  1.00K 1% CHIP  pkg 0402  page 133 : A = P3V3_STBY ; B = IRQ_BMC_PCH_SMI_LPC_N

(kicad_pcb
	(version 20260206)
	(generator "pcbnew")
	(generator_version "10.0")
	(general
		(thickness 1.6)
		(legacy_teardrops no)
	)
	(paper "A4")
	(title_block
		(title "Wiwynn_Tioga_Pass_MB.brd")
		(comment 1 "Tioga Pass / footprints 1431-1433 of 4770")
	)
	(layers
		(0 "F.Cu" signal "TOP")
		(4 "In1.Cu" signal "L2GND")
		(6 "In2.Cu" signal "L3")
		(8 "In3.Cu" signal "L4GND")
		(10 "In4.Cu" signal "L5")
		(12 "In5.Cu" signal "L6GND")
		(14 "In6.Cu" signal "L7VCC")
		(16 "In7.Cu" signal "L8VCC")
		(18 "In8.Cu" signal "L9GND")
		(20 "In9.Cu" signal "L10")
		(22 "In10.Cu" signal "L11GND")
		(24 "In11.Cu" signal "L12")
		(26 "In12.Cu" signal "L13GND")
		(2 "B.Cu" signal "BOTTOM")
		(9 "F.Adhes" user "F.Adhesive")
		(11 "B.Adhes" user "B.Adhesive")
		(13 "F.Paste" user "Package Geometry/Pastemask Top")
		(15 "B.Paste" user "Package Geometry/Pastemask Bottom")
		(5 "F.SilkS" user "Ref Des/Silkscreen Top")
		(7 "B.SilkS" user "Ref Des/Silkscreen Bottom")
		(1 "F.Mask" user "Board Geometry/Soldermask Top")
		(3 "B.Mask" user "Board Geometry/Soldermask Bottom")
		(17 "Dwgs.User" user "User.Drawings")
		(19 "Cmts.User" user "User.Comments")
		(21 "Eco1.User" user "User.Eco1")
		(23 "Eco2.User" user "User.Eco2")
		(25 "Edge.Cuts" user "Board Geometry/Outline")
		(27 "Margin" user)
		(31 "F.CrtYd" user "Package Geometry/Place Bound Top")
		(29 "B.CrtYd" user "Package Geometry/Place Bound Bottom")
		(35 "F.Fab" user "Ref Des/Assembly Top")
		(33 "B.Fab" user "Ref Des/Assembly Bottom")
	)
	(footprint ""
		(layer "F.Cu")
		(at 492.376714 -55.865268)
		(property "Reference" "C30W6"
			(at 0 0 0)
			(layer "F.SilkS")
			(hide yes)
			(effects
				(font
					(size 1.27 1.27)
				)
			)
		)
		(property "Value" "*"
			(at -0.0762 -6.2357 0)
			(unlocked yes)
			(layer "F.Fab")
			(hide yes)
			(effects
				(font
					(size 1.27 1.016)
					(thickness 0.1524)
				)
			)
		)
		(property "Device Type" "SC22U16V5MX-4-GP_SMD-BCG5-SC22A"
			(at -0.0762 -8.2677 0)
			(unlocked yes)
			(layer "F.Fab")
			(hide yes)
			(effects
				(font
					(size 1.27 1.016)
					(thickness 0.1524)
				)
			)
		)
		(duplicate_pad_numbers_are_jumpers no)
		(fp_line
			(start 0.635 0)
			(end -0.635 0)
			(stroke
				(width 0.508)
				(type default)
			)
			(layer "F.SilkS")
		)
		(fp_rect
			(start -0.9652 1.778)
			(end 0.9652 -1.778)
			(stroke
				(width 0)
				(type default)
			)
			(fill no)
			(layer "F.CrtYd")
		)
		(fp_poly
			(pts
				(xy -0.9652 -1.778) (xy 0.9652 -1.778) (xy 0.9652 1.778) (xy -0.9652 1.778)
			)
			(stroke
				(width 0)
				(type default)
			)
			(fill no)
			(layer "F.Fab")
		)
		(pad "1" smd rect
			(at 0 -0.9652)
			(size 1.397 1.143)
			(layers "F.Cu" "F.Mask" "F.Paste")
			(net "P5V_STBY_USBC")
		)
		(pad "2" smd rect
			(at 0 0.9652)
			(size 1.397 1.143)
			(layers "F.Cu" "F.Mask" "F.Paste")
			(net "GND")
		)
	)
	(footprint ""
		(layer "F.Cu")
		(at 399.669 -155.829 180)
		(property "Reference" "C8A2"
			(at 0 0 180)
			(layer "F.SilkS")
			(hide yes)
			(effects
				(font
					(size 1.27 1.27)
				)
			)
		)
		(property "Value" ""
			(at 0 0 180)
			(layer "F.Fab")
			(effects
				(font
					(size 1.27 1.27)
				)
			)
		)
		(duplicate_pad_numbers_are_jumpers no)
		(fp_poly
			(pts
				(xy 0.3048 -0.1016) (xy 0.3048 0.9906) (xy -0.3048 0.9906) (xy -0.3048 -0.1016)
			)
			(stroke
				(width 0)
				(type default)
			)
			(fill no)
			(layer "F.CrtYd")
		)
		(fp_line
			(start 0.3048 0.9906)
			(end 0.3048 -0.1016)
			(stroke
				(width 0.1)
				(type default)
			)
			(layer "F.Fab")
		)
		(fp_line
			(start 0.3048 -0.1016)
			(end -0.3048 -0.1016)
			(stroke
				(width 0.1)
				(type default)
			)
			(layer "F.Fab")
		)
		(fp_line
			(start -0.3048 0.9906)
			(end 0.3048 0.9906)
			(stroke
				(width 0.1)
				(type default)
			)
			(layer "F.Fab")
		)
		(fp_line
			(start -0.3048 -0.1016)
			(end -0.3048 0.9906)
			(stroke
				(width 0.1)
				(type default)
			)
			(layer "F.Fab")
		)
		(pad "1" smd rect
			(at 0 0 180)
			(size 0.508 0.508)
			(layers "F.Cu" "F.Mask" "F.Paste")
			(net "VR_PVNN_PCH_AVSP")
		)
		(pad "2" smd rect
			(at 0 0.889 180)
			(size 0.508 0.508)
			(layers "F.Cu" "F.Mask" "F.Paste")
			(net "VSENSE_PVNN_PCH_STBY_AVSN")
		)
		(zone
			(layer "F.Cu")
			(hatch none 0.5)
			(connect_pads
				(clearance 0)
			)
			(min_thickness 0.25)
			(keepout
				(tracks not_allowed)
				(vias allowed)
				(pads allowed)
				(copperpour not_allowed)
				(footprints allowed)
			)
			(placement
				(enabled no)
				(sheetname "")
			)
			(fill
				(thermal_gap 0.5)
				(thermal_bridge_width 0.5)
				(island_removal_mode 0)
			)
			(polygon
				(pts
					(xy 399.923 -156.464) (xy 399.415 -156.464) (xy 399.415 -156.083) (xy 399.923 -156.083)
				)
			)
		)
		(zone
			(layer "F.Cu")
			(hatch none 0.5)
			(connect_pads
				(clearance 0)
			)
			(min_thickness 0.25)
			(keepout
				(tracks allowed)
				(vias not_allowed)
				(pads allowed)
				(copperpour not_allowed)
				(footprints allowed)
			)
			(placement
				(enabled no)
				(sheetname "")
			)
			(fill
				(thermal_gap 0.5)
				(thermal_bridge_width 0.5)
				(island_removal_mode 0)
			)
			(polygon
				(pts
					(xy 399.923 -156.083) (xy 399.415 -156.083) (xy 399.415 -156.464) (xy 399.923 -156.464)
				)
			)
		)
	)
	(footprint ""
		(layer "F.Cu")
		(at 408.7495 -110.617 -90)
		(property "Reference" "R8C4"
			(at 0 0 270)
			(layer "F.SilkS")
			(hide yes)
			(effects
				(font
					(size 1.27 1.27)
				)
			)
		)
		(property "Value" ""
			(at 0 0 270)
			(layer "F.Fab")
			(effects
				(font
					(size 1.27 1.27)
				)
			)
		)
		(duplicate_pad_numbers_are_jumpers no)
		(fp_poly
			(pts
				(xy -0.2794 -0.1016) (xy 0.2794 -0.1016) (xy 0.2794 0.9906) (xy -0.2794 0.9906)
			)
			(stroke
				(width 0)
				(type default)
			)
			(fill no)
			(layer "F.CrtYd")
		)
		(fp_line
			(start -0.2794 0.9906)
			(end 0.2794 0.9906)
			(stroke
				(width 0.1)
				(type default)
			)
			(layer "F.Fab")
		)
		(fp_line
			(start 0.2794 0.9906)
			(end 0.2794 -0.1016)
			(stroke
				(width 0.1)
				(type default)
			)
			(layer "F.Fab")
		)
		(fp_line
			(start -0.2794 -0.1016)
			(end -0.2794 0.9906)
			(stroke
				(width 0.1)
				(type default)
			)
			(layer "F.Fab")
		)
		(fp_line
			(start 0.2794 -0.1016)
			(end -0.2794 -0.1016)
			(stroke
				(width 0.1)
				(type default)
			)
			(layer "F.Fab")
		)
		(pad "1" smd rect
			(at 0 0 270)
			(size 0.508 0.508)
			(layers "F.Cu" "F.Mask" "F.Paste")
			(net "P3V3_STBY")
		)
		(pad "2" smd rect
			(at 0 0.889 270)
			(size 0.508 0.508)
			(layers "F.Cu" "F.Mask" "F.Paste")
			(net "IRQ_BMC_PCH_SMI_LPC_N")
		)
		(zone
			(layer "F.Cu")
			(hatch none 0.5)
			(connect_pads
				(clearance 0)
			)
			(min_thickness 0.25)
			(keepout
				(tracks not_allowed)
				(vias allowed)
				(pads allowed)
				(copperpour not_allowed)
				(footprints allowed)
			)
			(placement
				(enabled no)
				(sheetname "")
			)
			(fill
				(thermal_gap 0.5)
				(thermal_bridge_width 0.5)
				(island_removal_mode 0)
			)
			(polygon
				(pts
					(xy 408.1145 -110.871) (xy 408.1145 -110.363) (xy 408.4955 -110.363) (xy 408.4955 -110.871)
				)
			)
		)
		(zone
			(layer "F.Cu")
			(hatch none 0.5)
			(connect_pads
				(clearance 0)
			)
			(min_thickness 0.25)
			(keepout
				(tracks allowed)
				(vias not_allowed)
				(pads allowed)
				(copperpour not_allowed)
				(footprints allowed)
			)
			(placement
				(enabled no)
				(sheetname "")
			)
			(fill
				(thermal_gap 0.5)
				(thermal_bridge_width 0.5)
				(island_removal_mode 0)
			)
			(polygon
				(pts
					(xy 408.4955 -110.871) (xy 408.4955 -110.363) (xy 408.1145 -110.363) (xy 408.1145 -110.871)
				)
			)
		)
	)
)
